# T6G (Grand Teton) — schematic netlist excerpt (pin names and nets, part order shuffled) for the footprints in the layout excerpt that follows; sources: Cadence DE-HDL packaged netlist, KiCad conversion of 04192023_DAF0TMB3IC0_F0TG_MB_C_brd_V02_OCP.brd

R3959  Q_RES  0 5% CHIP  pkg 0402LF  page 146 : A = P3V3_E1S_UV_0_R ; B = P3V3_E1S_UV_0
C200  Q_CAP  4.7UF 6.3V 20% X6S  pkg 0402  page 334 : A = P1V8_CPU1_RT_1D ; B = GND

(kicad_pcb
	(version 20260206)
	(generator "pcbnew")
	(generator_version "10.0")
	(general
		(thickness 1.6)
		(legacy_teardrops no)
	)
	(paper "A4")
	(title_block
		(title "04192023_DAF0TMB3IC0_F0TG_MB_C_brd_V02_OCP.brd")
		(comment 1 "Grand Teton / footprints 7414-7415 of 8354")
	)
	(layers
		(0 "F.Cu" signal "TOP")
		(4 "In1.Cu" signal "GND")
		(6 "In2.Cu" signal "IN1")
		(8 "In3.Cu" signal "GND1")
		(10 "In4.Cu" signal "IN2")
		(12 "In5.Cu" signal "GND2")
		(14 "In6.Cu" signal "IN3")
		(16 "In7.Cu" signal "GND3")
		(18 "In8.Cu" signal "VCC")
		(20 "In9.Cu" signal "VCC1")
		(22 "In10.Cu" signal "GND4")
		(24 "In11.Cu" signal "IN4")
		(26 "In12.Cu" signal "GND5")
		(28 "In13.Cu" signal "IN5")
		(30 "In14.Cu" signal "GND6")
		(32 "In15.Cu" signal "IN6")
		(34 "In16.Cu" signal "GND7")
		(2 "B.Cu" signal "BOTTOM")
		(9 "F.Adhes" user "F.Adhesive")
		(11 "B.Adhes" user "B.Adhesive")
		(13 "F.Paste" user "Package Geometry/Pastemask Top")
		(15 "B.Paste" user "Package Geometry/Pastemask Bottom")
		(5 "F.SilkS" user "Ref Des/Silkscreen Top")
		(7 "B.SilkS" user "Ref Des/Silkscreen Bottom")
		(1 "F.Mask" user "Board Geometry/Soldermask Top")
		(3 "B.Mask" user "Board Geometry/Soldermask Bottom")
		(17 "Dwgs.User" user "User.Drawings")
		(19 "Cmts.User" user "User.Comments")
		(21 "Eco1.User" user "User.Eco1")
		(23 "Eco2.User" user "User.Eco2")
		(25 "Edge.Cuts" user "Board Geometry/Outline")
		(27 "Margin" user)
		(31 "F.CrtYd" user "Package Geometry/Place Bound Top")
		(29 "B.CrtYd" user "Package Geometry/Place Bound Bottom")
		(35 "F.Fab" user "Ref Des/Assembly Top")
		(33 "B.Fab" user "Ref Des/Assembly Bottom")
	)
	(footprint ""
		(layer "B.Cu")
		(at 219.082112 -67.661028 -90)
		(property "Reference" "R3959"
			(at 0 0 90)
			(layer "B.SilkS")
			(hide yes)
			(effects
				(font
					(size 1.27 1.27)
				)
				(justify mirror)
			)
		)
		(property "Value" ""
			(at 0 0 90)
			(layer "B.Fab")
			(effects
				(font
					(size 1.27 1.27)
				)
				(justify mirror)
			)
		)
		(duplicate_pad_numbers_are_jumpers no)
		(fp_line
			(start -0.7874 0.4064)
			(end 0.7874 0.4064)
			(stroke
				(width 0.1524)
				(type default)
			)
			(layer "B.SilkS")
		)
		(fp_line
			(start 0.7874 0.4064)
			(end 0.7874 -0.4064)
			(stroke
				(width 0.1524)
				(type default)
			)
			(layer "B.SilkS")
		)
		(fp_line
			(start -0.7874 -0.4064)
			(end -0.7874 0.4064)
			(stroke
				(width 0.1524)
				(type default)
			)
			(layer "B.SilkS")
		)
		(fp_line
			(start 0.7874 -0.4064)
			(end -0.7874 -0.4064)
			(stroke
				(width 0.1524)
				(type default)
			)
			(layer "B.SilkS")
		)
		(fp_line
			(start -0.67945 0.3048)
			(end -0.120396 0.3048)
			(stroke
				(width 0.1)
				(type default)
			)
			(layer "B.Fab")
		)
		(fp_line
			(start -0.120396 0.3048)
			(end -0.120396 0.2794)
			(stroke
				(width 0.1)
				(type default)
			)
			(layer "B.Fab")
		)
		(fp_line
			(start 0.12065 0.3048)
			(end 0.67945 0.3048)
			(stroke
				(width 0.1)
				(type default)
			)
			(layer "B.Fab")
		)
		(fp_line
			(start 0.67945 0.3048)
			(end 0.67945 -0.305054)
			(stroke
				(width 0.1)
				(type default)
			)
			(layer "B.Fab")
		)
		(fp_line
			(start -0.120396 0.2794)
			(end 0.12065 0.2794)
			(stroke
				(width 0.1)
				(type default)
			)
			(layer "B.Fab")
		)
		(fp_line
			(start 0.12065 0.2794)
			(end 0.12065 0.3048)
			(stroke
				(width 0.1)
				(type default)
			)
			(layer "B.Fab")
		)
		(fp_line
			(start -0.12065 -0.2794)
			(end -0.12065 -0.3048)
			(stroke
				(width 0.1)
				(type default)
			)
			(layer "B.Fab")
		)
		(fp_line
			(start 0.12065 -0.2794)
			(end -0.12065 -0.2794)
			(stroke
				(width 0.1)
				(type default)
			)
			(layer "B.Fab")
		)
		(fp_line
			(start -0.67945 -0.3048)
			(end -0.67945 0.3048)
			(stroke
				(width 0.1)
				(type default)
			)
			(layer "B.Fab")
		)
		(fp_line
			(start -0.12065 -0.3048)
			(end -0.67945 -0.3048)
			(stroke
				(width 0.1)
				(type default)
			)
			(layer "B.Fab")
		)
		(fp_line
			(start 0.12065 -0.305054)
			(end 0.12065 -0.2794)
			(stroke
				(width 0.1)
				(type default)
			)
			(layer "B.Fab")
		)
		(fp_line
			(start 0.67945 -0.305054)
			(end 0.12065 -0.305054)
			(stroke
				(width 0.1)
				(type default)
			)
			(layer "B.Fab")
		)
		(pad "1" smd circle
			(at 0.40005 0 90)
			(size 0 0)
			(layers "B.Cu" "B.Mask" "B.Paste")
			(net "P3V3_E1S_UV_0_R")
		)
		(pad "2" smd circle
			(at -0.40005 0 90)
			(size 0 0)
			(layers "B.Cu" "B.Mask" "B.Paste")
			(net "P3V3_E1S_UV_0")
		)
	)
	(footprint ""
		(layer "B.Cu")
		(at 105.596182 -386.745988 -90)
		(property "Reference" "C200"
			(at 0 0 90)
			(layer "B.SilkS")
			(hide yes)
			(effects
				(font
					(size 1.27 1.27)
				)
				(justify mirror)
			)
		)
		(property "Value" ""
			(at 0 0 90)
			(layer "B.Fab")
			(effects
				(font
					(size 1.27 1.27)
				)
				(justify mirror)
			)
		)
		(duplicate_pad_numbers_are_jumpers no)
		(fp_line
			(start -0.7874 0.4064)
			(end 0.7874 0.4064)
			(stroke
				(width 0.1524)
				(type default)
			)
			(layer "B.SilkS")
		)
		(fp_line
			(start 0.7874 0.4064)
			(end 0.7874 -0.4064)
			(stroke
				(width 0.1524)
				(type default)
			)
			(layer "B.SilkS")
		)
		(fp_line
			(start -0.7874 -0.4064)
			(end -0.7874 0.4064)
			(stroke
				(width 0.1524)
				(type default)
			)
			(layer "B.SilkS")
		)
		(fp_line
			(start 0.7874 -0.4064)
			(end -0.7874 -0.4064)
			(stroke
				(width 0.1524)
				(type default)
			)
			(layer "B.SilkS")
		)
		(fp_line
			(start -0.67945 0.3048)
			(end -0.120396 0.3048)
			(stroke
				(width 0.1)
				(type default)
			)
			(layer "B.Fab")
		)
		(fp_line
			(start -0.120396 0.3048)
			(end -0.120396 0.2794)
			(stroke
				(width 0.1)
				(type default)
			)
			(layer "B.Fab")
		)
		(fp_line
			(start 0.12065 0.3048)
			(end 0.67945 0.3048)
			(stroke
				(width 0.1)
				(type default)
			)
			(layer "B.Fab")
		)
		(fp_line
			(start 0.67945 0.3048)
			(end 0.67945 -0.305054)
			(stroke
				(width 0.1)
				(type default)
			)
			(layer "B.Fab")
		)
		(fp_line
			(start -0.120396 0.2794)
			(end 0.12065 0.2794)
			(stroke
				(width 0.1)
				(type default)
			)
			(layer "B.Fab")
		)
		(fp_line
			(start 0.12065 0.2794)
			(end 0.12065 0.3048)
			(stroke
				(width 0.1)
				(type default)
			)
			(layer "B.Fab")
		)
		(fp_line
			(start -0.12065 -0.2794)
			(end -0.12065 -0.3048)
			(stroke
				(width 0.1)
				(type default)
			)
			(layer "B.Fab")
		)
		(fp_line
			(start 0.12065 -0.2794)
			(end -0.12065 -0.2794)
			(stroke
				(width 0.1)
				(type default)
			)
			(layer "B.Fab")
		)
		(fp_line
			(start -0.67945 -0.3048)
			(end -0.67945 0.3048)
			(stroke
				(width 0.1)
				(type default)
			)
			(layer "B.Fab")
		)
		(fp_line
			(start -0.12065 -0.3048)
			(end -0.67945 -0.3048)
			(stroke
				(width 0.1)
				(type default)
			)
			(layer "B.Fab")
		)
		(fp_line
			(start 0.12065 -0.305054)
			(end 0.12065 -0.2794)
			(stroke
				(width 0.1)
				(type default)
			)
			(layer "B.Fab")
		)
		(fp_line
			(start 0.67945 -0.305054)
			(end 0.12065 -0.305054)
			(stroke
				(width 0.1)
				(type default)
			)
			(layer "B.Fab")
		)
		(pad "1" smd circle
			(at 0.40005 0 90)
			(size 0 0)
			(layers "B.Cu" "B.Mask" "B.Paste")
			(net "P1V8_CPU1_RT_1D")
		)
		(pad "2" smd circle
			(at -0.40005 0 90)
			(size 0 0)
			(layers "B.Cu" "B.Mask" "B.Paste")
			(net "GND")
		)
	)
)
